#ISCELL
  mstr_misc prelim *
  *
#ISCELL
  mstr_symbols bom_note *
  *
#ISCELL
  mstr_symbols cad_note *
  *
#ISCELL
  mstr_symbols design_note *
  *
#ISCELL
  mstr_symbols intel_corp_bpage *
  *
#ISCELL
  mstr_standard offpage *
  page21_i10
#ISCELL
  mstr_standard offpage *
  page21_i106
#ISCELL
  mstr_standard offpage *
  page21_i107
#ISCELL
  mstr_standard offpage *
  page21_i108
#ISCELL
  mstr_standard offpage *
  page21_i11
#ISCELL
  mstr_standard offpage *
  page21_i111
#ISCELL
  mstr_standard offpage *
  page21_i12
#ISCELL
  mstr_standard offpage *
  page21_i133
#ISCELL
  mstr_standard offpage *
  page21_i134
#ISCELL
  mstr_standard offpage *
  page21_i135
#ISCELL
  mstr_standard offpage *
  page21_i136
#ISCELL
  mstr_standard offpage *
  page21_i137
#ISCELL
  mstr_standard offpage *
  page21_i145
#ISCELL
  mstr_standard offpage *
  page21_i146
#ISCELL
  mstr_standard offpage *
  page21_i147
#CELL
  mstr_discrete res *
  page21_i149
#ISCELL
  mstr_standard offpage *
  page21_i15
#CELL
  mstr_discrete res *
  page21_i150
#CELL
  mstr_discrete res *
  page21_i151
#CELL
  mstr_discrete res *
  page21_i152
#CELL
  mstr_discrete res *
  page21_i153
#CELL
  mstr_discrete res *
  page21_i154
#ISCELL
  mstr_standard offpage *
  page21_i155
#ISCELL
  mstr_standard offpage *
  page21_i156
#ISCELL
  mstr_standard offpage *
  page21_i157
#ISCELL
  mstr_symbols pvccio_cpu0 *
  page21_i158
#CELL
  mstr_discrete res *
  page21_i159
#CELL
  mstr_discrete res *
  page21_i161
#CELL
  mstr_discrete res *
  page21_i163
#CELL
  mstr_discrete res *
  page21_i164
#ISCELL
  mstr_standard offpage *
  page21_i169
#ISCELL
  mstr_standard offpage *
  page21_i170
#ISCELL
  mstr_standard offpage *
  page21_i172
#ISCELL
  mstr_standard offpage *
  page21_i175
#CELL
  mstr_discrete res *
  page21_i177
#CELL
  mstr_discrete res *
  page21_i178
#CELL
  mstr_discrete res *
  page21_i179
#ISCELL
  mstr_standard offpage *
  page21_i18
#CELL
  mstr_discrete res *
  page21_i180
#CELL
  mstr_discrete res *
  page21_i181
#CELL
  mstr_discrete res *
  page21_i182
#ISCELL
  mstr_symbols gnd *
  page21_i183
#CELL
  mstr_discrete res *
  page21_i184
#CELL
  mstr_discrete res *
  page21_i186
#ISCELL
  mstr_symbols gnd *
  page21_i187
#CELL
  mstr_discrete res *
  page21_i188
#CELL
  mstr_discrete res *
  page21_i189
#ISCELL
  mstr_standard offpage *
  page21_i196
#ISCELL
  mstr_standard offpage *
  page21_i197
#ISCELL
  mstr_standard offpage *
  page21_i2
#ISCELL
  mstr_standard offpage *
  page21_i200
#ISCELL
  mstr_standard offpage *
  page21_i201
#ISCELL
  mstr_standard offpage *
  page21_i202
#CELL
  mstr_discrete res *
  page21_i204
#ISCELL
  mstr_standard offpage *
  page21_i205
#ISCELL
  mstr_standard offpage *
  page21_i209
#ISCELL
  mstr_standard offpage *
  page21_i212
#ISCELL
  mstr_standard offpage *
  page21_i213
#ISCELL
  mstr_standard offpage *
  page21_i214
#ISCELL
  mstr_standard offpage *
  page21_i215
#CELL
  chpset_lib socket_p_mech_a *
  page21_i216
#CELL
  chpset_lib socket_p_mech_a *
  page21_i217
#CELL
  mstr_discrete res *
  page21_i219
#CELL
  mstr_discrete res *
  page21_i227
#ISCELL
  mstr_symbols p3v3_stby *
  page21_i228
#ISCELL
  mstr_standard offpage *
  page21_i233
#ISCELL
  mstr_standard offpage *
  page21_i234
#ISCELL
  mstr_standard offpage *
  page21_i235
#ISCELL
  mstr_standard offpage *
  page21_i236
#ISCELL
  mstr_standard offpage *
  page21_i237
#CELL
  mstr_discrete res *
  page21_i238
#CELL
  mstr_discrete res *
  page21_i239
#CELL
  mstr_discrete res *
  page21_i240
#CELL
  mstr_discrete res *
  page21_i241
#ISCELL
  mstr_symbols p3v3_stby *
  page21_i243
#CELL
  mstr_discrete res *
  page21_i244
#ISCELL
  mstr_standard offpage *
  page21_i247
#ISCELL
  mstr_standard offpage *
  page21_i254
#ISCELL
  mstr_standard offpage *
  page21_i255
#ISCELL
  mstr_standard offpage *
  page21_i256
#ISCELL
  mstr_symbols pvccio_cpu0 *
  page21_i257
#CELL
  mstr_discrete res *
  page21_i258
#CELL
  chpset_lib skx_ext_b *
  page21_i259
#ISCELL
  mstr_standard offpage *
  page21_i260
#ISCELL
  mstr_standard offpage *
  page21_i261
#ISCELL
  mstr_standard offpage *
  page21_i262
#ISCELL
  mstr_standard offpage *
  page21_i263
#ISCELL
  mstr_standard offpage *
  page21_i264
#ISCELL
  mstr_standard offpage *
  page21_i265
#ISCELL
  mstr_standard offpage *
  page21_i266
#ISCELL
  mstr_standard offpage *
  page21_i267
#ISCELL
  mstr_standard offpage *
  page21_i268
#ISCELL
  mstr_standard offpage *
  page21_i270
#ISCELL
  mstr_standard offpage *
  page21_i271
#ISCELL
  mstr_standard offpage *
  page21_i4
#ISCELL
  mstr_standard offpage *
  page21_i43
#ISCELL
  mstr_standard offpage *
  page21_i44
#ISCELL
  mstr_standard offpage *
  page21_i47
#ISCELL
  mstr_standard offpage *
  page21_i48
#ISCELL
  mstr_standard offpage *
  page21_i49
#ISCELL
  mstr_standard offpage *
  page21_i5
#ISCELL
  mstr_standard offpage *
  page21_i50
#ISCELL
  mstr_standard offpage *
  page21_i6
#ISCELL
  mstr_standard offpage *
  page21_i66
#ISCELL
  mstr_standard offpage *
  page21_i67
#ISCELL
  mstr_standard offpage *
  page21_i68
#ISCELL
  mstr_standard offpage *
  page21_i69
#ISCELL
  mstr_standard offpage *
  page21_i7
#ISCELL
  mstr_standard offpage *
  page21_i71
#ISCELL
  mstr_standard offpage *
  page21_i72
#ISCELL
  mstr_standard offpage *
  page21_i74
#ISCELL
  mstr_standard offpage *
  page21_i75
#ISCELL
  mstr_standard offpage *
  page21_i76
#ISCELL
  mstr_standard offpage *
  page21_i77
#ISCELL
  mstr_standard offpage *
  page21_i78
#ISCELL
  mstr_standard offpage *
  page21_i79
#ISCELL
  mstr_standard offpage *
  page21_i8
#ISCELL
  mstr_standard offpage *
  page21_i80
#ISCELL
  mstr_standard offpage *
  page21_i9
